# BASEBOARD_FAB2 (Tioga Pass) — schematic netlist excerpt (pin names and nets, part order shuffled) for the footprints in the layout excerpt that follows; sources: Cadence DE-HDL packaged netlist, KiCad conversion of Wiwynn_Tioga_Pass_MB.brd

J4A1  SCONN288_H44441004  SCONN  pkg PIP  page 53
  \12v\(1)  = P12V_NVDIMM_DEF
  VSS(93)  = GND
  DQ(4)  = M_F_DQ<5>
  VSS(92)  = GND
  DQ(0)  = M_F_DQ<1>
  VSS(91)  = GND
  DQS9P  = M_F_DQS_DP<9>
  DQS9N  = M_F_DQS_DN<9>
  VSS(90)  = GND
  DQ(6)  = M_F_DQ<7>
  VSS(89)  = GND
  DQ(2)  = M_F_DQ<3>
  VSS(88)  = GND
  DQ(12)  = M_F_DQ<13>
  VSS(87)  = GND
  DQ(8)  = M_F_DQ<9>
  VSS(86)  = GND
  DQS10P  = M_F_DQS_DP<10>
  DQS10N  = M_F_DQS_DN<10>
  VSS(85)  = GND
  DQ(14)  = M_F_DQ<15>
  VSS(84)  = GND
  DQ(10)  = M_F_DQ<11>
  VSS(83)  = GND
  DQ(20)  = M_F_DQ<21>
  VSS(82)  = GND
  DQ(16)  = M_F_DQ<17>
  VSS(81)  = GND
  DQS11P  = M_F_DQS_DP<11>
  DQS11N  = M_F_DQS_DN<11>
  VSS(80)  = GND
  DQ(22)  = M_F_DQ<23>
  VSS(79)  = GND
  DQ(18)  = M_F_DQ<19>
  VSS(78)  = GND
  DQ(28)  = M_F_DQ<29>
  VSS(77)  = GND
  DQ(24)  = M_F_DQ<25>
  VSS(76)  = GND
  DQS12P  = M_F_DQS_DP<12>
  DQS12N  = M_F_DQS_DN<12>
  VSS(75)  = GND
  DQ(30)  = M_F_DQ<31>
  VSS(74)  = GND
  DQ(26)  = M_F_DQ<27>
  VSS(73)  = GND
  CB(4)  = M_F_ECC<5>
  VSS(72)  = GND
  CB(0)  = M_F_ECC<1>
  VSS(71)  = GND
  DQS17P  = M_F_DQS_DP<17>
  DQS17N  = M_F_DQS_DN<17>
  VSS(70)  = GND
  CB(6)  = M_F_ECC<7>
  VSS(69)  = GND
  CB(2)  = M_F_ECC<3>
  VSS(68)  = GND
  RESET_N  = M_DEF_RST_N
  VDD(25)  = PVDDQ_DEF
  CKE(0)  = M_F_CKE<0>
  VDD(24)  = PVDDQ_DEF
  ACT_N  = M_F_ACT_N
  BG(0)  = M_F_BG<0>
  VDD(23)  = PVDDQ_DEF
  A12  = M_F_MA<12>
  A9  = M_F_MA<9>
  VDD(22)  = PVDDQ_DEF
  A8  = M_F_MA<8>
  A6  = M_F_MA<6>
  VDD(21)  = PVDDQ_DEF
  A3  = M_F_MA<3>
  A1  = M_F_MA<1>
  VDD(20)  = PVDDQ_DEF
  CK0P  = M_F_CLK_DP<0>
  CK0N  = M_F_CLK_DN<0>
  VDD(19)  = PVDDQ_DEF
  VTT(1)  = PVTT_DEF
  EVENT_N  = FM_DIMM_EVENT_COD_N
  A0  = M_F_MA<0>
  VDD(18)  = PVDDQ_DEF
  BA(0)  = M_F_BA<0>
  A16_RAS_N  = M_F_MA<16>
  VDD(17)  = PVDDQ_DEF
  S0_N  = M_F_CS_N<0>
  VDD(16)  = PVDDQ_DEF
  A15_CAS_N  = M_F_MA<15>
  ODT(0)  = M_F_ODT<0>
  VDD(15)  = PVDDQ_DEF
  S1_N  = M_F_CS_N<1>
  VDD(14)  = PVDDQ_DEF
  ODT(1)  = M_F_ODT<1>
  VDD(13)  = PVDDQ_DEF
  S2_N_C(0)  = M_F_CS_N<2>
  VSS(67)  = GND
  DQ(36)  = M_F_DQ<37>
  VSS(66)  = GND
  DQ(32)  = M_F_DQ<33>
  VSS(65)  = GND
  DQS13P  = M_F_DQS_DP<13>
  DQS13N  = M_F_DQS_DN<13>
  VSS(64)  = GND
  DQ(38)  = M_F_DQ<39>
  VSS(63)  = GND
  DQ(34)  = M_F_DQ<35>
  VSS(62)  = GND
  DQ(44)  = M_F_DQ<45>
  VSS(61)  = GND
  DQ(40)  = M_F_DQ<41>
  VSS(60)  = GND
  DQS14P  = M_F_DQS_DP<14>
  DQS14N  = M_F_DQS_DN<14>
  VSS(59)  = GND
  DQ(46)  = M_F_DQ<47>
  VSS(58)  = GND
  DQ(42)  = M_F_DQ<43>
  VSS(57)  = GND
  DQ(52)  = M_F_DQ<53>
  VSS(56)  = GND
  DQ(48)  = M_F_DQ<49>
  VSS(55)  = GND
  DQS15P  = M_F_DQS_DP<15>
  DQS15N  = M_F_DQS_DN<15>
  VSS(54)  = GND
  DQ(54)  = M_F_DQ<55>
  VSS(53)  = GND
  DQ(50)  = M_F_DQ<51>
  VSS(52)  = GND
  DQ(60)  = M_F_DQ<61>
  VSS(51)  = GND
  DQ(56)  = M_F_DQ<57>
  VSS(50)  = GND
  DQS16P  = M_F_DQS_DP<16>
  DQS16N  = M_F_DQS_DN<16>
  VSS(49)  = GND
  DQ(62)  = M_F_DQ<63>
  VSS(48)  = GND
  DQ(58)  = M_F_DQ<59>
  VSS(47)  = GND
  SA(0)  = GND
  SA(1)  = GND
  SCL  = SMB_DDR_DEF_VPP_SCL
  VPP(4)  = PVPP_DEF
  VPP(3)  = PVPP_DEF
  RFU(2)  = TP_CH_F_DIMM_F0_RFU_2
  \12v\(0)  = P12V_NVDIMM_DEF
  VREFCA  = M_F_VREF
  VSS(46)  = GND
  DQ(5)  = M_F_DQ<4>
  VSS(45)  = GND
  DQ(1)  = M_F_DQ<0>
  VSS(44)  = GND
  DQS0N  = M_F_DQS_DN<0>
  DQS0P  = M_F_DQS_DP<0>
  VSS(43)  = GND
  DQ(7)  = M_F_DQ<6>
  VSS(42)  = GND
  DQ(3)  = M_F_DQ<2>
  VSS(41)  = GND
  DQ(13)  = M_F_DQ<12>
  VSS(40)  = GND
  DQ(9)  = M_F_DQ<8>
  VSS(39)  = GND
  DQS1N  = M_F_DQS_DN<1>
  DQS1P  = M_F_DQS_DP<1>
  VSS(38)  = GND
  DQ(15)  = M_F_DQ<14>
  VSS(37)  = GND
  DQ(11)  = M_F_DQ<10>
  VSS(36)  = GND
  DQ(21)  = M_F_DQ<20>
  VSS(35)  = GND
  DQ(17)  = M_F_DQ<16>
  VSS(34)  = GND
  DQS2N  = M_F_DQS_DN<2>
  DQS2P  = M_F_DQS_DP<2>
  VSS(33)  = GND
  DQ(23)  = M_F_DQ<22>
  VSS(32)  = GND
  DQ(19)  = M_F_DQ<18>
  VSS(31)  = GND
  DQ(29)  = M_F_DQ<28>
  VSS(30)  = GND
  DQ(25)  = M_F_DQ<24>
  VSS(29)  = GND
  DQS3N  = M_F_DQS_DN<3>
  DQS3P  = M_F_DQS_DP<3>
  VSS(28)  = GND
  DQ(31)  = M_F_DQ<30>
  VSS(27)  = GND
  DQ(27)  = M_F_DQ<26>
  VSS(26)  = GND
  CB(5)  = M_F_ECC<4>
  VSS(25)  = GND
  CB(1)  = M_F_ECC<0>
  VSS(24)  = GND
  DQS8N  = M_F_DQS_DN<8>
  DQS8P  = M_F_DQS_DP<8>
  VSS(23)  = GND
  CB(7)  = M_F_ECC<6>
  VSS(22)  = GND
  CB(3)  = M_F_ECC<2>
  VSS(21)  = GND
  CKE(1)  = M_F_CKE<1>
  VDD(12)  = PVDDQ_DEF
  RFU(0)  = TP_CH_F_DIMM_F0_RFU_0
  VDD(11)  = PVDDQ_DEF
  BG(1)  = M_F_BG<1>
  ALERT_N  = M_F_ALERT_N
  VDD(10)  = PVDDQ_DEF
  A11  = M_F_MA<11>
  A7  = M_F_MA<7>
  VDD(9)  = PVDDQ_DEF
  A5  = M_F_MA<5>
  A4  = M_F_MA<4>
  VDD(8)  = PVDDQ_DEF
  A2  = M_F_MA<2>
  VDD(7)  = PVDDQ_DEF
  CK1P  = M_F_CLK_DP<1>
  CK1N  = M_F_CLK_DN<1>
  VDD(6)  = PVDDQ_DEF
  VTT(0)  = PVTT_DEF
  PAR  = M_F_PAR
  VDD(5)  = PVDDQ_DEF
  BA(1)  = M_F_BA<1>
  A10  = M_F_MA<10>
  VDD(4)  = PVDDQ_DEF
  RFU(1)  = TP_CH_F_DIMM_F0_RFU_1
  A14_WE_N  = M_F_MA<14>
  VDD(3)  = PVDDQ_DEF
  SAVE_N_NC  = FM_ADR_COMPLETE_DEF_N
  VDD(2)  = PVDDQ_DEF
  A13  = M_F_MA<13>
  VDD(1)  = PVDDQ_DEF
  A17  = M_F_MA<17>
  C(2)  = M_F_C<2>
  VDD(0)  = PVDDQ_DEF
  S3_N_C(1)  = M_F_CS_N<3>
  SA(2)  = PVPP_DEF
  VSS(20)  = GND
  DQ(37)  = M_F_DQ<36>
  VSS(19)  = GND
  DQ(33)  = M_F_DQ<32>
  VSS(18)  = GND
  DQS4N  = M_F_DQS_DN<4>
  DQS4P  = M_F_DQS_DP<4>
  VSS(17)  = GND
  DQ(39)  = M_F_DQ<38>
  VSS(16)  = GND
  DQ(35)  = M_F_DQ<34>
  VSS(15)  = GND
  DQ(45)  = M_F_DQ<44>
  VSS(14)  = GND
  DQ(41)  = M_F_DQ<40>
  VSS(13)  = GND
  DQS5N  = M_F_DQS_DN<5>
  DQS5P  = M_F_DQS_DP<5>
  VSS(12)  = GND
  DQ(47)  = M_F_DQ<46>
  VSS(11)  = GND
  DQ(43)  = M_F_DQ<42>
  VSS(10)  = GND
  DQ(53)  = M_F_DQ<52>
  VSS(9)  = GND
  DQ(49)  = M_F_DQ<48>
  VSS(8)  = GND
  DQS6N  = M_F_DQS_DN<6>
  DQS6P  = M_F_DQS_DP<6>
  VSS(7)  = GND
  DQ(55)  = M_F_DQ<54>
  VSS(6)  = GND
  DQ(51)  = M_F_DQ<50>
  VSS(5)  = GND
  DQ(61)  = M_F_DQ<60>
  VSS(4)  = GND
  DQ(57)  = M_F_DQ<56>
  VSS(3)  = GND
  DQS7N  = M_F_DQS_DN<7>
  DQS7P  = M_F_DQS_DP<7>
  VSS(2)  = GND
  DQ(63)  = M_F_DQ<62>
  VSS(1)  = GND
  DQ(59)  = M_F_DQ<58>
  VSS(0)  = GND
  VDDSPD  = PVPP_DEF
  SDA  = SMB_DDR_DEF_VPP_SDA
  VPP(1)  = PVPP_DEF
  VPP(0)  = PVPP_DEF
  VPP(2)  = PVPP_DEF

(kicad_pcb
	(version 20260206)
	(generator "pcbnew")
	(generator_version "10.0")
	(general
		(thickness 1.6)
		(legacy_teardrops no)
	)
	(paper "A4")
	(title_block
		(title "Wiwynn_Tioga_Pass_MB.brd")
		(comment 1 "Tioga Pass / footprint 431 of 4770 (J4A1), pads 203-251 of 291")
	)
	(layers
		(0 "F.Cu" signal "TOP")
		(4 "In1.Cu" signal "L2GND")
		(6 "In2.Cu" signal "L3")
		(8 "In3.Cu" signal "L4GND")
		(10 "In4.Cu" signal "L5")
		(12 "In5.Cu" signal "L6GND")
		(14 "In6.Cu" signal "L7VCC")
		(16 "In7.Cu" signal "L8VCC")
		(18 "In8.Cu" signal "L9GND")
		(20 "In9.Cu" signal "L10")
		(22 "In10.Cu" signal "L11GND")
		(24 "In11.Cu" signal "L12")
		(26 "In12.Cu" signal "L13GND")
		(2 "B.Cu" signal "BOTTOM")
		(9 "F.Adhes" user "F.Adhesive")
		(11 "B.Adhes" user "B.Adhesive")
		(13 "F.Paste" user "Package Geometry/Pastemask Top")
		(15 "B.Paste" user "Package Geometry/Pastemask Bottom")
		(5 "F.SilkS" user "Ref Des/Silkscreen Top")
		(7 "B.SilkS" user "Ref Des/Silkscreen Bottom")
		(1 "F.Mask" user "Board Geometry/Soldermask Top")
		(3 "B.Mask" user "Board Geometry/Soldermask Bottom")
		(17 "Dwgs.User" user "User.Drawings")
		(19 "Cmts.User" user "User.Comments")
		(21 "Eco1.User" user "User.Eco1")
		(23 "Eco2.User" user "User.Eco2")
		(25 "Edge.Cuts" user "Board Geometry/Outline")
		(27 "Margin" user)
		(31 "F.CrtYd" user "Package Geometry/Place Bound Top")
		(29 "B.CrtYd" user "Package Geometry/Place Bound Bottom")
		(35 "F.Fab" user "Ref Des/Assembly Top")
		(33 "B.Fab" user "Ref Des/Assembly Bottom")
	)
	(footprint ""
		(layer "F.Cu")
		(at 194.700398 -152.273 90)
		(property "Reference" "J4A1"
			(at -2.699512 42.53611 0)
			(unlocked yes)
			(layer "F.SilkS")
			(effects
				(font
					(size 0.7874 0.5842)
					(thickness 0.1524)
				)
				(justify left)
			)
		)
		(property "Value" ""
			(at 0 0 90)
			(layer "F.Fab")
			(effects
				(font
					(size 1.27 1.27)
				)
			)
		)
		(duplicate_pad_numbers_are_jumpers no)
		(pad "200" smd rect
			(at 4.59994 46.74997 90)
			(size 1.8034 0.508)
			(layers "F.Cu" "F.Mask" "F.Paste")
			(net "GND")
		)
		(pad "201" smd rect
			(at 4.59994 47.600108 90)
			(size 1.8034 0.508)
			(layers "F.Cu" "F.Mask" "F.Paste")
			(net "M_F_ECC<2>")
		)
		(pad "202" smd rect
			(at 4.59994 48.449992 90)
			(size 1.8034 0.508)
			(layers "F.Cu" "F.Mask" "F.Paste")
			(net "GND")
		)
		(pad "203" smd rect
			(at 4.59994 49.299876 90)
			(size 1.8034 0.508)
			(layers "F.Cu" "F.Mask" "F.Paste")
			(net "M_F_CKE<1>")
		)
		(pad "204" smd rect
			(at 4.59994 50.150014 90)
			(size 1.8034 0.508)
			(layers "F.Cu" "F.Mask" "F.Paste")
			(net "PVDDQ_DEF")
		)
		(pad "205" smd rect
			(at 4.59994 50.999898 90)
			(size 1.8034 0.508)
			(layers "F.Cu" "F.Mask" "F.Paste")
			(net "TP_CH_F_DIMM_F0_RFU_0")
		)
		(pad "206" smd rect
			(at 4.59994 51.850036 90)
			(size 1.8034 0.508)
			(layers "F.Cu" "F.Mask" "F.Paste")
			(net "PVDDQ_DEF")
		)
		(pad "207" smd rect
			(at 4.59994 52.69992 90)
			(size 1.8034 0.508)
			(layers "F.Cu" "F.Mask" "F.Paste")
			(net "M_F_BG<1>")
		)
		(pad "208" smd rect
			(at 4.59994 53.550058 90)
			(size 1.8034 0.508)
			(layers "F.Cu" "F.Mask" "F.Paste")
			(net "M_F_ALERT_N")
		)
		(pad "209" smd rect
			(at 4.59994 54.399942 90)
			(size 1.8034 0.508)
			(layers "F.Cu" "F.Mask" "F.Paste")
			(net "PVDDQ_DEF")
		)
		(pad "210" smd rect
			(at 4.59994 55.25008 90)
			(size 1.8034 0.508)
			(layers "F.Cu" "F.Mask" "F.Paste")
			(net "M_F_MA<11>")
		)
		(pad "211" smd rect
			(at 4.59994 56.099964 90)
			(size 1.8034 0.508)
			(layers "F.Cu" "F.Mask" "F.Paste")
			(net "M_F_MA<7>")
		)
		(pad "212" smd rect
			(at 4.59994 56.950102 90)
			(size 1.8034 0.508)
			(layers "F.Cu" "F.Mask" "F.Paste")
			(net "PVDDQ_DEF")
		)
		(pad "213" smd rect
			(at 4.59994 57.799986 90)
			(size 1.8034 0.508)
			(layers "F.Cu" "F.Mask" "F.Paste")
			(net "M_F_MA<5>")
		)
		(pad "214" smd rect
			(at 4.59994 58.650124 90)
			(size 1.8034 0.508)
			(layers "F.Cu" "F.Mask" "F.Paste")
			(net "M_F_MA<4>")
		)
		(pad "215" smd rect
			(at 4.59994 59.500008 90)
			(size 1.8034 0.508)
			(layers "F.Cu" "F.Mask" "F.Paste")
			(net "PVDDQ_DEF")
		)
		(pad "216" smd rect
			(at 4.59994 60.349892 90)
			(size 1.8034 0.508)
			(layers "F.Cu" "F.Mask" "F.Paste")
			(net "M_F_MA<2>")
		)
		(pad "217" smd rect
			(at 4.59994 61.20003 90)
			(size 1.8034 0.508)
			(layers "F.Cu" "F.Mask" "F.Paste")
			(net "PVDDQ_DEF")
		)
		(pad "218" smd rect
			(at 4.59994 62.049914 90)
			(size 1.8034 0.508)
			(layers "F.Cu" "F.Mask" "F.Paste")
			(net "M_F_CLK_DP<1>")
		)
		(pad "219" smd rect
			(at 4.59994 62.900052 90)
			(size 1.8034 0.508)
			(layers "F.Cu" "F.Mask" "F.Paste")
			(net "M_F_CLK_DN<1>")
		)
		(pad "220" smd rect
			(at 4.59994 63.749936 90)
			(size 1.8034 0.508)
			(layers "F.Cu" "F.Mask" "F.Paste")
			(net "PVDDQ_DEF")
		)
		(pad "221" smd rect
			(at 4.59994 64.600074 90)
			(size 1.8034 0.508)
			(layers "F.Cu" "F.Mask" "F.Paste")
			(net "PVTT_DEF")
		)
		(pad "222" smd rect
			(at 4.59994 70.550024 90)
			(size 1.8034 0.508)
			(layers "F.Cu" "F.Mask" "F.Paste")
			(net "M_F_PAR")
		)
		(pad "223" smd rect
			(at 4.59994 71.399908 90)
			(size 1.8034 0.508)
			(layers "F.Cu" "F.Mask" "F.Paste")
			(net "PVDDQ_DEF")
		)
		(pad "224" smd rect
			(at 4.59994 72.250046 90)
			(size 1.8034 0.508)
			(layers "F.Cu" "F.Mask" "F.Paste")
			(net "M_F_BA<1>")
		)
		(pad "225" smd rect
			(at 4.59994 73.09993 90)
			(size 1.8034 0.508)
			(layers "F.Cu" "F.Mask" "F.Paste")
			(net "M_F_MA<10>")
		)
		(pad "226" smd rect
			(at 4.59994 73.950068 90)
			(size 1.8034 0.508)
			(layers "F.Cu" "F.Mask" "F.Paste")
			(net "PVDDQ_DEF")
		)
		(pad "227" smd rect
			(at 4.59994 74.799952 90)
			(size 1.8034 0.508)
			(layers "F.Cu" "F.Mask" "F.Paste")
			(net "TP_CH_F_DIMM_F0_RFU_1")
		)
		(pad "228" smd rect
			(at 4.59994 75.65009 90)
			(size 1.8034 0.508)
			(layers "F.Cu" "F.Mask" "F.Paste")
			(net "M_F_MA<14>")
		)
		(pad "229" smd rect
			(at 4.59994 76.499974 90)
			(size 1.8034 0.508)
			(layers "F.Cu" "F.Mask" "F.Paste")
			(net "PVDDQ_DEF")
		)
		(pad "230" smd rect
			(at 4.59994 77.350112 90)
			(size 1.8034 0.508)
			(layers "F.Cu" "F.Mask" "F.Paste")
			(net "FM_ADR_COMPLETE_DEF_N")
		)
		(pad "231" smd rect
			(at 4.59994 78.199996 90)
			(size 1.8034 0.508)
			(layers "F.Cu" "F.Mask" "F.Paste")
			(net "PVDDQ_DEF")
		)
		(pad "232" smd rect
			(at 4.59994 79.04988 90)
			(size 1.8034 0.508)
			(layers "F.Cu" "F.Mask" "F.Paste")
			(net "M_F_MA<13>")
		)
		(pad "233" smd rect
			(at 4.59994 79.900018 90)
			(size 1.8034 0.508)
			(layers "F.Cu" "F.Mask" "F.Paste")
			(net "PVDDQ_DEF")
		)
		(pad "234" smd rect
			(at 4.59994 80.749902 90)
			(size 1.8034 0.508)
			(layers "F.Cu" "F.Mask" "F.Paste")
			(net "M_F_MA<17>")
		)
		(pad "235" smd rect
			(at 4.59994 81.60004 90)
			(size 1.8034 0.508)
			(layers "F.Cu" "F.Mask" "F.Paste")
			(net "M_F_C<2>")
		)
		(pad "236" smd rect
			(at 4.59994 82.449924 90)
			(size 1.8034 0.508)
			(layers "F.Cu" "F.Mask" "F.Paste")
			(net "PVDDQ_DEF")
		)
		(pad "237" smd rect
			(at 4.59994 83.300062 90)
			(size 1.8034 0.508)
			(layers "F.Cu" "F.Mask" "F.Paste")
			(net "M_F_CS_N<3>")
		)
		(pad "238" smd rect
			(at 4.59994 84.149946 90)
			(size 1.8034 0.508)
			(layers "F.Cu" "F.Mask" "F.Paste")
			(net "PVPP_DEF")
		)
		(pad "239" smd rect
			(at 4.59994 85.000084 90)
			(size 1.8034 0.508)
			(layers "F.Cu" "F.Mask" "F.Paste")
			(net "GND")
		)
		(pad "240" smd rect
			(at 4.59994 85.849968 90)
			(size 1.8034 0.508)
			(layers "F.Cu" "F.Mask" "F.Paste")
			(net "M_F_DQ<36>")
		)
		(pad "241" smd rect
			(at 4.59994 86.700106 90)
			(size 1.8034 0.508)
			(layers "F.Cu" "F.Mask" "F.Paste")
			(net "GND")
		)
		(pad "242" smd rect
			(at 4.59994 87.54999 90)
			(size 1.8034 0.508)
			(layers "F.Cu" "F.Mask" "F.Paste")
			(net "M_F_DQ<32>")
		)
		(pad "243" smd rect
			(at 4.59994 88.399874 90)
			(size 1.8034 0.508)
			(layers "F.Cu" "F.Mask" "F.Paste")
			(net "GND")
		)
		(pad "244" smd rect
			(at 4.59994 89.250012 90)
			(size 1.8034 0.508)
			(layers "F.Cu" "F.Mask" "F.Paste")
			(net "M_F_DQS_DN<4>")
		)
		(pad "245" smd rect
			(at 4.59994 90.099896 90)
			(size 1.8034 0.508)
			(layers "F.Cu" "F.Mask" "F.Paste")
			(net "M_F_DQS_DP<4>")
		)
		(pad "246" smd rect
			(at 4.59994 90.950034 90)
			(size 1.8034 0.508)
			(layers "F.Cu" "F.Mask" "F.Paste")
			(net "GND")
		)
		(pad "247" smd rect
			(at 4.59994 91.799918 90)
			(size 1.8034 0.508)
			(layers "F.Cu" "F.Mask" "F.Paste")
			(net "M_F_DQ<38>")
		)
		(pad "248" smd rect
			(at 4.59994 92.650056 90)
			(size 1.8034 0.508)
			(layers "F.Cu" "F.Mask" "F.Paste")
			(net "GND")
		)
	)
)
